(kicad_pcb
	(version 20260206)
	(generator "pcbnew")
	(generator_version "10.0")
	(general
		(thickness 1.6)
		(legacy_teardrops no)
	)
	(paper "A4")
	(title_block
		(title "baseboard — 13948-1b.1110WZS1818.brd")
		(comment 1 "Honey Badger (Wiwynn) / footprints 575-579 of 2523")
	)
	(layers
		(0 "F.Cu" signal "TOP")
		(4 "In1.Cu" signal "L2GND")
		(6 "In2.Cu" signal "L3")
		(8 "In3.Cu" signal "L4VCC")
		(10 "In4.Cu" signal "L5VCC")
		(12 "In5.Cu" signal "L6")
		(14 "In6.Cu" signal "L7GND")
		(2 "B.Cu" signal "BOTTOM")
		(9 "F.Adhes" user "F.Adhesive")
		(11 "B.Adhes" user "B.Adhesive")
		(13 "F.Paste" user "Package Geometry/Pastemask Top")
		(15 "B.Paste" user "Package Geometry/Pastemask Bottom")
		(5 "F.SilkS" user "Ref Des/Silkscreen Top")
		(7 "B.SilkS" user "Ref Des/Silkscreen Bottom")
		(1 "F.Mask" user "Board Geometry/Soldermask Top")
		(3 "B.Mask" user "Board Geometry/Soldermask Bottom")
		(17 "Dwgs.User" user "User.Drawings")
		(19 "Cmts.User" user "User.Comments")
		(21 "Eco1.User" user "User.Eco1")
		(23 "Eco2.User" user "User.Eco2")
		(25 "Edge.Cuts" user "Board Geometry/Outline")
		(27 "Margin" user)
		(31 "F.CrtYd" user "Package Geometry/Place Bound Top")
		(29 "B.CrtYd" user "Package Geometry/Place Bound Bottom")
		(35 "F.Fab" user "Ref Des/Assembly Top")
		(33 "B.Fab" user "Ref Des/Assembly Bottom")
	)
	(footprint ""
		(layer "F.Cu")
		(at 277.358094 -25.791668 90)
		(property "Reference" "L8"
			(at 0 0 90)
			(layer "F.SilkS")
			(hide yes)
			(effects
				(font
					(size 1.27 1.27)
				)
			)
		)
		(property "Value" "DLW21HN900SQ2LGP-U"
			(at -0.0889 -2.7813 90)
			(unlocked yes)
			(layer "F.Fab")
			(hide yes)
			(effects
				(font
					(size 1.016 1.016)
					(thickness 0.1524)
				)
			)
		)
		(property "Device Type" "L2012-4P-1MH40"
			(at -0.0889 -4.3053 90)
			(unlocked yes)
			(layer "F.Fab")
			(hide yes)
			(effects
				(font
					(size 1.016 1.016)
					(thickness 0.1524)
				)
			)
		)
		(duplicate_pad_numbers_are_jumpers no)
		(fp_line
			(start 1.5494 -1.0668)
			(end 1.5494 1.0668)
			(stroke
				(width 0.1524)
				(type default)
			)
			(layer "F.SilkS")
		)
		(fp_line
			(start -1.5494 -1.0668)
			(end 1.5494 -1.0668)
			(stroke
				(width 0.1524)
				(type default)
			)
			(layer "F.SilkS")
		)
		(fp_line
			(start 1.5494 1.0668)
			(end -1.5494 1.0668)
			(stroke
				(width 0.1524)
				(type default)
			)
			(layer "F.SilkS")
		)
		(fp_line
			(start -1.5494 1.0668)
			(end -1.5494 -1.0668)
			(stroke
				(width 0.1524)
				(type default)
			)
			(layer "F.SilkS")
		)
		(fp_line
			(start 1.0668 1.1811)
			(end 0.6858 1.1811)
			(stroke
				(width 0.3302)
				(type default)
			)
			(layer "F.SilkS")
		)
		(fp_poly
			(pts
				(xy 1.500124 1.768856) (xy 0.230124 1.768856) (xy 0.865124 1.133856)
			)
			(stroke
				(width 0)
				(type default)
			)
			(fill yes)
			(layer "F.SilkS")
		)
		(fp_rect
			(start -1.0033 0.5969)
			(end 1.0033 -0.5969)
			(stroke
				(width 0)
				(type default)
			)
			(fill no)
			(layer "F.CrtYd")
		)
		(fp_poly
			(pts
				(xy -1.8034 1.3208) (xy -1.8034 -1.3208) (xy 1.8034 -1.3208) (xy 1.8034 0.0508) (xy 1.0033 0.0508)
				(xy 1.0033 -0.5969) (xy -1.0033 -0.5969) (xy -1.0033 0.5969) (xy 1.0033 0.5969) (xy 1.0033 0.0762)
				(xy 1.8034 0.0762) (xy 1.8034 1.3208)
			)
			(stroke
				(width 0)
				(type default)
			)
			(fill no)
			(layer "F.CrtYd")
		)
		(fp_rect
			(start -1.8034 1.3208)
			(end 1.8034 -1.3208)
			(stroke
				(width 0)
				(type default)
			)
			(fill no)
			(layer "F.Fab")
		)
		(pad "1" smd rect
			(at 0.8382 0.4826 90)
			(size 0.9144 0.6604)
			(layers "F.Cu" "F.Mask" "F.Paste")
			(net "USB_DP_R")
		)
		(pad "2" smd rect
			(at -0.8382 0.4826 90)
			(size 0.9144 0.6604)
			(layers "F.Cu" "F.Mask" "F.Paste")
			(net "USB_P1_F_DP1")
		)
		(pad "3" smd rect
			(at -0.8382 -0.4826 90)
			(size 0.9144 0.6604)
			(layers "F.Cu" "F.Mask" "F.Paste")
			(net "USB_P1_F_DN1")
		)
		(pad "4" smd rect
			(at 0.8382 -0.4826 90)
			(size 0.9144 0.6604)
			(layers "F.Cu" "F.Mask" "F.Paste")
			(net "USB_DN_R")
		)
		(zone
			(layer "F.Cu")
			(hatch none 0.5)
			(connect_pads
				(clearance 0)
			)
			(min_thickness 0.25)
			(keepout
				(tracks not_allowed)
				(vias allowed)
				(pads allowed)
				(copperpour not_allowed)
				(footprints allowed)
			)
			(placement
				(enabled no)
				(sheetname "")
			)
			(fill
				(thermal_gap 0.5)
				(thermal_bridge_width 0.5)
				(island_removal_mode 0)
			)
			(polygon
				(pts
					(xy 278.170894 -25.410668) (xy 277.510494 -25.410668) (xy 277.510494 -24.496268) (xy 277.205694 -24.496268)
					(xy 277.205694 -25.410668) (xy 276.545294 -25.410668) (xy 276.545294 -26.172668) (xy 277.205694 -26.172668)
					(xy 277.205694 -27.087068) (xy 277.510494 -27.087068) (xy 277.510494 -26.172668) (xy 278.170894 -26.172668)
				)
			)
		)
		(zone
			(layer "F.Cu")
			(hatch none 0.5)
			(connect_pads
				(clearance 0)
			)
			(min_thickness 0.25)
			(keepout
				(tracks allowed)
				(vias not_allowed)
				(pads allowed)
				(copperpour not_allowed)
				(footprints allowed)
			)
			(placement
				(enabled no)
				(sheetname "")
			)
			(fill
				(thermal_gap 0.5)
				(thermal_bridge_width 0.5)
				(island_removal_mode 0)
			)
			(polygon
				(pts
					(xy 278.170894 -25.410668) (xy 277.510494 -25.410668) (xy 277.510494 -24.496268) (xy 277.205694 -24.496268)
					(xy 277.205694 -25.410668) (xy 276.545294 -25.410668) (xy 276.545294 -26.172668) (xy 277.205694 -26.172668)
					(xy 277.205694 -27.087068) (xy 277.510494 -27.087068) (xy 277.510494 -26.172668) (xy 278.170894 -26.172668)
				)
			)
		)
	)
	(footprint ""
		(layer "F.Cu")
		(at 173.778164 -22.490176 90)
		(property "Reference" "R398"
			(at 0 0 90)
			(layer "F.SilkS")
			(hide yes)
			(effects
				(font
					(size 1.27 1.27)
				)
			)
		)
		(property "Value" "49D9R5F-2-GP"
			(at 0 -8.9535 90)
			(unlocked yes)
			(layer "F.Fab")
			(hide yes)
			(effects
				(font
					(size 1.27 1.016)
					(thickness 0.1524)
				)
			)
		)
		(property "Device Type" "R805H24"
			(at 0 -10.6299 90)
			(unlocked yes)
			(layer "F.Fab")
			(hide yes)
			(effects
				(font
					(size 1.27 1.016)
					(thickness 0.1524)
				)
			)
		)
		(duplicate_pad_numbers_are_jumpers no)
		(fp_line
			(start 0.889 -1.7018)
			(end -0.889 -1.7018)
			(stroke
				(width 0.1524)
				(type default)
			)
			(layer "F.SilkS")
		)
		(fp_line
			(start 0.889 -1.7018)
			(end 0.889 -0.381)
			(stroke
				(width 0.1524)
				(type default)
			)
			(layer "F.SilkS")
		)
		(fp_line
			(start -0.889 -1.7018)
			(end -0.889 0.2794)
			(stroke
				(width 0.1524)
				(type default)
			)
			(layer "F.SilkS")
		)
		(fp_line
			(start -0.889 0.0762)
			(end -0.889 1.7018)
			(stroke
				(width 0.1524)
				(type default)
			)
			(layer "F.SilkS")
		)
		(fp_line
			(start 0.889 1.7018)
			(end 0.889 -0.508)
			(stroke
				(width 0.1524)
				(type default)
			)
			(layer "F.SilkS")
		)
		(fp_line
			(start -0.889 1.7018)
			(end 0.889 1.7018)
			(stroke
				(width 0.1524)
				(type default)
			)
			(layer "F.SilkS")
		)
		(fp_poly
			(pts
				(xy 0.9652 -1.778) (xy 0.9652 1.778) (xy -0.9652 1.778) (xy -0.9652 -1.778)
			)
			(stroke
				(width 0)
				(type default)
			)
			(fill no)
			(layer "F.CrtYd")
		)
		(fp_rect
			(start -0.9652 1.778)
			(end 0.9652 -1.778)
			(stroke
				(width 0)
				(type default)
			)
			(fill no)
			(layer "F.Fab")
		)
		(pad "1" smd rect
			(at 0 -0.9652 90)
			(size 1.397 1.143)
			(layers "F.Cu" "F.Mask" "F.Paste")
			(net "P3V3_STBY")
		)
		(pad "2" smd rect
			(at 0 0.9652 90)
			(size 1.397 1.143)
			(layers "F.Cu" "F.Mask" "F.Paste")
			(net "BCM5221_TX_C_DP")
		)
	)
	(footprint ""
		(layer "F.Cu")
		(at 6.300216 -214.68588 -90)
		(property "Reference" "R623"
			(at 0 0 270)
			(layer "F.SilkS")
			(hide yes)
			(effects
				(font
					(size 1.27 1.27)
				)
			)
		)
		(property "Value" "10KR2F-2-GP"
			(at 0.064008 -3.993896 270)
			(unlocked yes)
			(layer "F.Fab")
			(hide yes)
			(effects
				(font
					(size 1.016 1.016)
					(thickness 0.1524)
				)
			)
		)
		(property "Device Type" "R402H16"
			(at 0.064008 -5.517896 270)
			(unlocked yes)
			(layer "F.Fab")
			(hide yes)
			(effects
				(font
					(size 1.016 1.016)
					(thickness 0.1524)
				)
			)
		)
		(duplicate_pad_numbers_are_jumpers no)
		(fp_line
			(start -0.508 -0.9398)
			(end -0.508 0.9398)
			(stroke
				(width 0.1524)
				(type default)
			)
			(layer "F.SilkS")
		)
		(fp_line
			(start 0.508 -0.9398)
			(end -0.508 -0.9398)
			(stroke
				(width 0.1524)
				(type default)
			)
			(layer "F.SilkS")
		)
		(fp_rect
			(start -0.508 0.9398)
			(end 0.508 -0.9398)
			(stroke
				(width 0)
				(type default)
			)
			(fill no)
			(layer "F.CrtYd")
		)
		(fp_rect
			(start -0.508 0.9398)
			(end 0.508 -0.9398)
			(stroke
				(width 0)
				(type default)
			)
			(fill no)
			(layer "F.Fab")
		)
		(pad "1" smd custom
			(at 0 -0.4445 270)
			(size 0.1397 0.1397)
			(layers "F.Cu" "F.Mask" "F.Paste")
			(net "PRSNT_AND_3")
			(options
				(clearance outline)
				(anchor circle)
			)
			(primitives
				(gr_poly
					(pts
						(arc
							(start -0.1778 -0.2794)
							(mid -0.249642 -0.249642)
							(end -0.2794 -0.1778)
						)
						(arc
							(start -0.2794 0.1778)
							(mid -0.249642 0.249642)
							(end -0.1778 0.2794)
						)
						(arc
							(start 0.1778 0.2794)
							(mid 0.249642 0.249642)
							(end 0.2794 0.1778)
						)
						(arc
							(start 0.2794 -0.1778)
							(mid 0.249642 -0.249642)
							(end 0.1778 -0.2794)
						)
					)
					(width 0)
					(fill yes)
				)
			)
		)
		(pad "2" smd custom
			(at 0 0.4445 270)
			(size 0.1397 0.1397)
			(layers "F.Cu" "F.Mask" "F.Paste")
			(net "GND")
			(options
				(clearance outline)
				(anchor circle)
			)
			(primitives
				(gr_poly
					(pts
						(arc
							(start -0.1778 -0.2794)
							(mid -0.249642 -0.249642)
							(end -0.2794 -0.1778)
						)
						(arc
							(start -0.2794 0.1778)
							(mid -0.249642 0.249642)
							(end -0.1778 0.2794)
						)
						(arc
							(start 0.1778 0.2794)
							(mid 0.249642 0.249642)
							(end 0.2794 0.1778)
						)
						(arc
							(start 0.2794 -0.1778)
							(mid 0.249642 -0.249642)
							(end 0.1778 -0.2794)
						)
					)
					(width 0)
					(fill yes)
				)
			)
		)
	)
	(footprint ""
		(layer "F.Cu")
		(at 340.868 -110.871)
		(property "Reference" "PU1"
			(at 0 0 0)
			(layer "F.SilkS")
			(hide yes)
			(effects
				(font
					(size 1.27 1.27)
				)
			)
		)
		(property "Value" "TPS53312RGTR-GP"
			(at 4.9784 -6.9342 0)
			(unlocked yes)
			(layer "F.Fab")
			(hide yes)
			(effects
				(font
					(size 1.016 1.016)
					(thickness 0.1524)
				)
			)
		)
		(property "Device Type" "QFN16G3-G1D7H40"
			(at 4.9784 -8.4582 0)
			(unlocked yes)
			(layer "F.Fab")
			(hide yes)
			(effects
				(font
					(size 1.016 1.016)
					(thickness 0.1524)
				)
			)
		)
		(duplicate_pad_numbers_are_jumpers no)
		(fp_line
			(start -2.5146 -2.5146)
			(end -2.5146 -1.2446)
			(stroke
				(width 0.1524)
				(type default)
			)
			(layer "F.SilkS")
		)
		(fp_line
			(start -2.5146 1.2446)
			(end -2.5146 2.5146)
			(stroke
				(width 0.1524)
				(type default)
			)
			(layer "F.SilkS")
		)
		(fp_line
			(start -2.5146 2.5146)
			(end -1.2446 2.5146)
			(stroke
				(width 0.1524)
				(type default)
			)
			(layer "F.SilkS")
		)
		(fp_line
			(start -2.262124 -0.750062)
			(end -2.770124 -0.750062)
			(stroke
				(width 0.1524)
				(type default)
			)
			(layer "F.SilkS")
		)
		(fp_line
			(start -1.2446 -2.5146)
			(end -2.5146 -2.5146)
			(stroke
				(width 0.1524)
				(type default)
			)
			(layer "F.SilkS")
		)
		(fp_line
			(start -0.249936 2.262124)
			(end -0.249936 3.024124)
			(stroke
				(width 0.1524)
				(type default)
			)
			(layer "F.SilkS")
		)
		(fp_line
			(start 1.2446 2.5146)
			(end 2.5146 2.5146)
			(stroke
				(width 0.1524)
				(type default)
			)
			(layer "F.SilkS")
		)
		(fp_line
			(start 2.262124 -0.249936)
			(end 2.770124 -0.249936)
			(stroke
				(width 0.1524)
				(type default)
			)
			(layer "F.SilkS")
		)
		(fp_line
			(start 2.5146 2.5146)
			(end 2.5146 1.2446)
			(stroke
				(width 0.1524)
				(type default)
			)
			(layer "F.SilkS")
		)
		(fp_poly
			(pts
				(xy 2.5146 -2.5146) (xy 1.2446 -2.5146) (xy 2.5146 -1.2446)
			)
			(stroke
				(width 0)
				(type default)
			)
			(fill yes)
			(layer "F.SilkS")
		)
		(fp_rect
			(start -1.4986 1.4986)
			(end 1.4986 -1.4986)
			(stroke
				(width 0)
				(type default)
			)
			(fill no)
			(layer "F.CrtYd")
		)
		(fp_poly
			(pts
				(xy 2.5146 -1.4986) (xy -1.4986 -1.4986) (xy -1.4986 1.4986) (xy 1.4986 1.4986) (xy 1.4986 -1.4859)
				(xy 2.5146 -1.4859) (xy 2.5146 2.5146) (xy -2.5146 2.5146) (xy -2.5146 -2.5146) (xy 2.5146 -2.5146)
			)
			(stroke
				(width 0)
				(type default)
			)
			(fill no)
			(layer "F.CrtYd")
		)
		(fp_rect
			(start -2.5146 2.5146)
			(end 2.5146 -2.5146)
			(stroke
				(width 0)
				(type default)
			)
			(fill no)
			(layer "F.Fab")
		)
		(pad "1" smd rect
			(at 0.750062 -1.550924)
			(size 0.3048 0.9144)
			(layers "F.Cu" "F.Mask" "F.Paste")
			(net "P5V_STBY_VFB")
		)
		(pad "2" smd rect
			(at 0.249936 -1.538224)
			(size 0.3048 0.9398)
			(layers "F.Cu" "F.Mask" "F.Paste")
			(net "P5V_STBY_VRG5")
		)
		(pad "3" smd rect
			(at -0.249936 -1.538224)
			(size 0.3048 0.9398)
			(layers "F.Cu" "F.Mask" "F.Paste")
			(net "P5V_STBY_SS")
		)
		(pad "4" smd rect
			(at -0.750062 -1.550924)
			(size 0.3048 0.9144)
			(layers "F.Cu" "F.Mask" "F.Paste")
			(net "AGND_P5V_STBY")
		)
		(pad "5" smd rect
			(at -1.550924 -0.750062)
			(size 0.9144 0.3048)
			(layers "F.Cu" "F.Mask" "F.Paste")
			(net "P5V_STBY_PG")
		)
		(pad "6" smd rect
			(at -1.538224 -0.249936)
			(size 0.9398 0.3048)
			(layers "F.Cu" "F.Mask" "F.Paste")
			(net "P5V_STBY_EN_R")
		)
		(pad "7" smd rect
			(at -1.538224 0.249936)
			(size 0.9398 0.3048)
			(layers "F.Cu" "F.Mask" "F.Paste")
			(net "GND")
		)
		(pad "8" smd rect
			(at -1.550924 0.750062)
			(size 0.9144 0.3048)
			(layers "F.Cu" "F.Mask" "F.Paste")
			(net "GND")
		)
		(pad "9" smd rect
			(at -0.750062 1.550924)
			(size 0.3048 0.9144)
			(layers "F.Cu" "F.Mask" "F.Paste")
			(net "P5V_STBY_SW")
		)
		(pad "10" smd rect
			(at -0.249936 1.538224)
			(size 0.3048 0.9398)
			(layers "F.Cu" "F.Mask" "F.Paste")
			(net "P5V_STBY_SW")
		)
		(pad "11" smd rect
			(at 0.249936 1.538224)
			(size 0.3048 0.9398)
			(layers "F.Cu" "F.Mask" "F.Paste")
			(net "P5V_STBY_SW")
		)
		(pad "12" smd rect
			(at 0.750062 1.550924)
			(size 0.3048 0.9144)
			(layers "F.Cu" "F.Mask" "F.Paste")
			(net "P5V_STBY_VBST")
		)
		(pad "13" smd rect
			(at 1.550924 0.750062)
			(size 0.9144 0.3048)
			(layers "F.Cu" "F.Mask" "F.Paste")
			(net "P5V_STBY_VIN")
		)
		(pad "14" smd rect
			(at 1.538224 0.249936)
			(size 0.9398 0.3048)
			(layers "F.Cu" "F.Mask" "F.Paste")
			(net "P5V_STBY_VIN")
		)
		(pad "15" smd rect
			(at 1.538224 -0.249936)
			(size 0.9398 0.3048)
			(layers "F.Cu" "F.Mask" "F.Paste")
			(net "P5V_STBY_VCC")
		)
		(pad "16" smd rect
			(at 1.550924 -0.750062)
			(size 0.9144 0.3048)
			(layers "F.Cu" "F.Mask" "F.Paste")
			(net "P5V_STBY_VO")
		)
		(pad "17" smd rect
			(at 0 0)
			(size 1.6764 1.6764)
			(layers "F.Cu" "F.Mask" "F.Paste")
			(net "GND")
		)
	)
	(footprint ""
		(layer "F.Cu")
		(at 301.371 -97.028)
		(property "Reference" "U134"
			(at 0 0 0)
			(layer "F.SilkS")
			(hide yes)
			(effects
				(font
					(size 1.27 1.27)
				)
			)
		)
		(property "Value" "TMP75AIDGKR-GP"
			(at -0.1143 -9.1948 0)
			(unlocked yes)
			(layer "F.Fab")
			(hide yes)
			(effects
				(font
					(size 1.016 1.016)
					(thickness 0.1524)
				)
			)
		)
		(property "Device Type" "MSOP8-1H44"
			(at -0.1143 -10.795 0)
			(unlocked yes)
			(layer "F.Fab")
			(hide yes)
			(effects
				(font
					(size 1.016 1.016)
					(thickness 0.1524)
				)
			)
		)
		(duplicate_pad_numbers_are_jumpers no)
		(fp_line
			(start -1.9558 -1.016)
			(end -1.9558 1.016)
			(stroke
				(width 0.1524)
				(type default)
			)
			(layer "F.SilkS")
		)
		(fp_line
			(start -1.9558 -0.5461)
			(end -1.4478 -0.0381)
			(stroke
				(width 0.1524)
				(type default)
			)
			(layer "F.SilkS")
		)
		(fp_line
			(start -1.9558 1.016)
			(end 1.0795 1.016)
			(stroke
				(width 0.1524)
				(type default)
			)
			(layer "F.SilkS")
		)
		(fp_line
			(start -1.778 1.0922)
			(end -1.778 3.048)
			(stroke
				(width 0.508)
				(type default)
			)
			(layer "F.SilkS")
		)
		(fp_line
			(start -1.4478 -0.0381)
			(end -1.9558 0.4699)
			(stroke
				(width 0.1524)
				(type default)
			)
			(layer "F.SilkS")
		)
		(fp_line
			(start 1.0795 -1.016)
			(end -1.9558 -1.016)
			(stroke
				(width 0.1524)
				(type default)
			)
			(layer "F.SilkS")
		)
		(fp_line
			(start 1.0795 1.016)
			(end 1.0795 -1.016)
			(stroke
				(width 0.1524)
				(type default)
			)
			(layer "F.SilkS")
		)
		(fp_poly
			(pts
				(xy -1.1557 -1.016) (xy -1.1557 1.016) (xy 1.1557 1.016) (xy 1.1557 -1.016)
			)
			(stroke
				(width 0)
				(type default)
			)
			(fill yes)
			(layer "F.SilkS")
		)
		(fp_rect
			(start -1.4986 2.4511)
			(end 1.4986 -2.4511)
			(stroke
				(width 0)
				(type default)
			)
			(fill no)
			(layer "F.CrtYd")
		)
		(fp_poly
			(pts
				(xy -2.032 3.302) (xy -2.032 -3.302) (xy 2.032 -3.302) (xy 2.032 -2.1209) (xy 1.4986 -2.1209) (xy 1.4986 -2.4511)
				(xy -1.4986 -2.4511) (xy -1.4986 2.4511) (xy 1.4986 2.4511) (xy 1.4986 -2.1082) (xy 2.032 -2.1082)
				(xy 2.032 3.302)
			)
			(stroke
				(width 0)
				(type default)
			)
			(fill no)
			(layer "F.CrtYd")
		)
		(fp_rect
			(start -2.032 3.302)
			(end 2.032 -3.302)
			(stroke
				(width 0)
				(type default)
			)
			(fill no)
			(layer "F.Fab")
		)
		(pad "1" smd rect
			(at -0.97536 2.05486)
			(size 0.3556 1.524)
			(layers "F.Cu" "F.Mask" "F.Paste")
			(net "TEMP_2_SDA")
		)
		(pad "2" smd rect
			(at -0.32512 2.05486)
			(size 0.3556 1.524)
			(layers "F.Cu" "F.Mask" "F.Paste")
			(net "TEMP_2_SCL")
		)
		(pad "3" smd rect
			(at 0.32512 2.05486)
			(size 0.3556 1.524)
			(layers "F.Cu" "F.Mask" "F.Paste")
			(net "TEMP_2_ALERT")
		)
		(pad "4" smd rect
			(at 0.97536 2.05486)
			(size 0.3556 1.524)
			(layers "F.Cu" "F.Mask" "F.Paste")
			(net "GND")
		)
		(pad "5" smd rect
			(at 0.97536 -2.05486)
			(size 0.3556 1.524)
			(layers "F.Cu" "F.Mask" "F.Paste")
			(net "TEMP_2_A2")
		)
		(pad "6" smd rect
			(at 0.32512 -2.05486)
			(size 0.3556 1.524)
			(layers "F.Cu" "F.Mask" "F.Paste")
			(net "TEMP_2_A1")
		)
		(pad "7" smd rect
			(at -0.32512 -2.05486)
			(size 0.3556 1.524)
			(layers "F.Cu" "F.Mask" "F.Paste")
			(net "TEMP_2_A0")
		)
		(pad "8" smd rect
			(at -0.97536 -2.05486)
			(size 0.3556 1.524)
			(layers "F.Cu" "F.Mask" "F.Paste")
			(net "P3V3_STBY")
		)
	)
)
